# S9S_MB_2U (Grand Teton) — schematic netlist excerpt (pin names and nets, part order shuffled) for the footprints in the layout excerpt that follows; sources: Cadence DE-HDL packaged netlist, KiCad conversion of 03242023_DA0F0TMBIJ0_F0T_Motherboard_J_brd_V01_OCP.brd

R1381  Q_RES  1K 1% CHIP  pkg 0402LF  page 239 : A = P3V3_AUX ; B = FM_BMC_CPU_FBRK_OUT_N
R3509  Q_RES  10K 1% CHIP  pkg 0402LF  page 151 : A = GPU_FPGA_RST_R1_BUF_N ; B = GND

(kicad_pcb
	(version 20260206)
	(generator "pcbnew")
	(generator_version "10.0")
	(general
		(thickness 1.6)
		(legacy_teardrops no)
	)
	(paper "A4")
	(title_block
		(title "03242023_DA0F0TMBIJ0_F0T_Motherboard_J_brd_V01_OCP.brd")
		(comment 1 "Grand Teton / footprints 1683-1684 of 6105")
	)
	(layers
		(0 "F.Cu" signal "TOP")
		(4 "In1.Cu" signal "GND")
		(6 "In2.Cu" signal "IN1")
		(8 "In3.Cu" signal "GND1")
		(10 "In4.Cu" signal "IN2")
		(12 "In5.Cu" signal "GND2")
		(14 "In6.Cu" signal "IN3")
		(16 "In7.Cu" signal "GND3")
		(18 "In8.Cu" signal "VCC")
		(20 "In9.Cu" signal "VCC1")
		(22 "In10.Cu" signal "GND4")
		(24 "In11.Cu" signal "IN4")
		(26 "In12.Cu" signal "GND5")
		(28 "In13.Cu" signal "IN5")
		(30 "In14.Cu" signal "GND6")
		(32 "In15.Cu" signal "IN6")
		(34 "In16.Cu" signal "GND7")
		(2 "B.Cu" signal "BOTTOM")
		(9 "F.Adhes" user "F.Adhesive")
		(11 "B.Adhes" user "B.Adhesive")
		(13 "F.Paste" user "Package Geometry/Pastemask Top")
		(15 "B.Paste" user "Package Geometry/Pastemask Bottom")
		(5 "F.SilkS" user "Ref Des/Silkscreen Top")
		(7 "B.SilkS" user "Ref Des/Silkscreen Bottom")
		(1 "F.Mask" user "Board Geometry/Soldermask Top")
		(3 "B.Mask" user "Board Geometry/Soldermask Bottom")
		(17 "Dwgs.User" user "User.Drawings")
		(19 "Cmts.User" user "User.Comments")
		(21 "Eco1.User" user "User.Eco1")
		(23 "Eco2.User" user "User.Eco2")
		(25 "Edge.Cuts" user "Board Geometry/Outline")
		(27 "Margin" user)
		(31 "F.CrtYd" user "Package Geometry/Place Bound Top")
		(29 "B.CrtYd" user "Package Geometry/Place Bound Bottom")
		(35 "F.Fab" user "Ref Des/Assembly Top")
		(33 "B.Fab" user "Ref Des/Assembly Bottom")
	)
	(footprint ""
		(layer "F.Cu")
		(at 368.1984 -101.171248 -90)
		(property "Reference" "R1381"
			(at 0 0 270)
			(layer "F.SilkS")
			(hide yes)
			(effects
				(font
					(size 1.27 1.27)
				)
			)
		)
		(property "Value" ""
			(at 0 0 270)
			(layer "F.Fab")
			(effects
				(font
					(size 1.27 1.27)
				)
			)
		)
		(duplicate_pad_numbers_are_jumpers no)
		(fp_line
			(start -0.7874 0.4064)
			(end -0.7874 -0.4064)
			(stroke
				(width 0.1524)
				(type default)
			)
			(layer "F.SilkS")
		)
		(fp_line
			(start 0.7874 0.4064)
			(end -0.7874 0.4064)
			(stroke
				(width 0.1524)
				(type default)
			)
			(layer "F.SilkS")
		)
		(fp_line
			(start -0.7874 -0.4064)
			(end 0.7874 -0.4064)
			(stroke
				(width 0.1524)
				(type default)
			)
			(layer "F.SilkS")
		)
		(fp_line
			(start 0.7874 -0.4064)
			(end 0.7874 0.4064)
			(stroke
				(width 0.1524)
				(type default)
			)
			(layer "F.SilkS")
		)
		(fp_line
			(start -0.67945 0.3048)
			(end -0.67945 -0.305054)
			(stroke
				(width 0.1)
				(type default)
			)
			(layer "F.Fab")
		)
		(fp_line
			(start -0.12065 0.3048)
			(end -0.67945 0.3048)
			(stroke
				(width 0.1)
				(type default)
			)
			(layer "F.Fab")
		)
		(fp_line
			(start 0.120396 0.3048)
			(end 0.120396 0.2794)
			(stroke
				(width 0.1)
				(type default)
			)
			(layer "F.Fab")
		)
		(fp_line
			(start 0.67945 0.3048)
			(end 0.120396 0.3048)
			(stroke
				(width 0.1)
				(type default)
			)
			(layer "F.Fab")
		)
		(fp_line
			(start -0.12065 0.2794)
			(end -0.12065 0.3048)
			(stroke
				(width 0.1)
				(type default)
			)
			(layer "F.Fab")
		)
		(fp_line
			(start 0.120396 0.2794)
			(end -0.12065 0.2794)
			(stroke
				(width 0.1)
				(type default)
			)
			(layer "F.Fab")
		)
		(fp_line
			(start -0.12065 -0.2794)
			(end 0.12065 -0.2794)
			(stroke
				(width 0.1)
				(type default)
			)
			(layer "F.Fab")
		)
		(fp_line
			(start 0.12065 -0.2794)
			(end 0.12065 -0.3048)
			(stroke
				(width 0.1)
				(type default)
			)
			(layer "F.Fab")
		)
		(fp_line
			(start 0.12065 -0.3048)
			(end 0.67945 -0.3048)
			(stroke
				(width 0.1)
				(type default)
			)
			(layer "F.Fab")
		)
		(fp_line
			(start 0.67945 -0.3048)
			(end 0.67945 0.3048)
			(stroke
				(width 0.1)
				(type default)
			)
			(layer "F.Fab")
		)
		(fp_line
			(start -0.67945 -0.305054)
			(end -0.12065 -0.305054)
			(stroke
				(width 0.1)
				(type default)
			)
			(layer "F.Fab")
		)
		(fp_line
			(start -0.12065 -0.305054)
			(end -0.12065 -0.2794)
			(stroke
				(width 0.1)
				(type default)
			)
			(layer "F.Fab")
		)
		(pad "1" smd circle
			(at -0.40005 0 270)
			(size 0 0)
			(layers "F.Cu" "F.Mask" "F.Paste")
			(net "P3V3_AUX")
		)
		(pad "2" smd circle
			(at 0.40005 0 270)
			(size 0 0)
			(layers "F.Cu" "F.Mask" "F.Paste")
			(net "FM_BMC_CPU_FBRK_OUT_N")
		)
	)
	(footprint ""
		(layer "F.Cu")
		(at 120.37822 -417.383468)
		(property "Reference" "R3509"
			(at 0 0 0)
			(layer "F.SilkS")
			(hide yes)
			(effects
				(font
					(size 1.27 1.27)
				)
			)
		)
		(property "Value" ""
			(at 0 0 0)
			(layer "F.Fab")
			(effects
				(font
					(size 1.27 1.27)
				)
			)
		)
		(duplicate_pad_numbers_are_jumpers no)
		(fp_line
			(start -0.7874 -0.4064)
			(end 0.7874 -0.4064)
			(stroke
				(width 0.1524)
				(type default)
			)
			(layer "F.SilkS")
		)
		(fp_line
			(start -0.7874 0.4064)
			(end -0.7874 -0.4064)
			(stroke
				(width 0.1524)
				(type default)
			)
			(layer "F.SilkS")
		)
		(fp_line
			(start 0.7874 -0.4064)
			(end 0.7874 0.4064)
			(stroke
				(width 0.1524)
				(type default)
			)
			(layer "F.SilkS")
		)
		(fp_line
			(start 0.7874 0.4064)
			(end -0.7874 0.4064)
			(stroke
				(width 0.1524)
				(type default)
			)
			(layer "F.SilkS")
		)
		(fp_line
			(start -0.67945 -0.305054)
			(end -0.12065 -0.305054)
			(stroke
				(width 0.1)
				(type default)
			)
			(layer "F.Fab")
		)
		(fp_line
			(start -0.67945 0.3048)
			(end -0.67945 -0.305054)
			(stroke
				(width 0.1)
				(type default)
			)
			(layer "F.Fab")
		)
		(fp_line
			(start -0.12065 -0.305054)
			(end -0.12065 -0.2794)
			(stroke
				(width 0.1)
				(type default)
			)
			(layer "F.Fab")
		)
		(fp_line
			(start -0.12065 -0.2794)
			(end 0.12065 -0.2794)
			(stroke
				(width 0.1)
				(type default)
			)
			(layer "F.Fab")
		)
		(fp_line
			(start -0.12065 0.2794)
			(end -0.12065 0.3048)
			(stroke
				(width 0.1)
				(type default)
			)
			(layer "F.Fab")
		)
		(fp_line
			(start -0.12065 0.3048)
			(end -0.67945 0.3048)
			(stroke
				(width 0.1)
				(type default)
			)
			(layer "F.Fab")
		)
		(fp_line
			(start 0.120396 0.2794)
			(end -0.12065 0.2794)
			(stroke
				(width 0.1)
				(type default)
			)
			(layer "F.Fab")
		)
		(fp_line
			(start 0.120396 0.3048)
			(end 0.120396 0.2794)
			(stroke
				(width 0.1)
				(type default)
			)
			(layer "F.Fab")
		)
		(fp_line
			(start 0.12065 -0.3048)
			(end 0.67945 -0.3048)
			(stroke
				(width 0.1)
				(type default)
			)
			(layer "F.Fab")
		)
		(fp_line
			(start 0.12065 -0.2794)
			(end 0.12065 -0.3048)
			(stroke
				(width 0.1)
				(type default)
			)
			(layer "F.Fab")
		)
		(fp_line
			(start 0.67945 -0.3048)
			(end 0.67945 0.3048)
			(stroke
				(width 0.1)
				(type default)
			)
			(layer "F.Fab")
		)
		(fp_line
			(start 0.67945 0.3048)
			(end 0.120396 0.3048)
			(stroke
				(width 0.1)
				(type default)
			)
			(layer "F.Fab")
		)
		(pad "1" smd circle
			(at -0.40005 0)
			(size 0 0)
			(layers "F.Cu" "F.Mask" "F.Paste")
			(net "GPU_FPGA_RST_R1_BUF_N")
		)
		(pad "2" smd circle
			(at 0.40005 0)
			(size 0 0)
			(layers "F.Cu" "F.Mask" "F.Paste")
			(net "GND")
		)
	)
)
